(kicad_pcb
	(version 20260206)
	(generator "pcbnew")
	(generator_version "10.0")
	(general
		(thickness 1.6)
		(legacy_teardrops no)
	)
	(paper "A4")
	(title_block
		(title "01162023_DA0F0TEBIF0_F0T_Expander_BD_F_brd_V02_OCP.brd")
		(comment 1 "Grand Teton / footprints 4944-4949 of 9728")
	)
	(layers
		(0 "F.Cu" signal "TOP")
		(4 "In1.Cu" signal "GND")
		(6 "In2.Cu" signal "VCC")
		(8 "In3.Cu" signal "VCC1")
		(10 "In4.Cu" signal "GND1")
		(12 "In5.Cu" signal "IN1")
		(14 "In6.Cu" signal "GND2")
		(16 "In7.Cu" signal "IN2")
		(18 "In8.Cu" signal "GND3")
		(20 "In9.Cu" signal "IN3")
		(22 "In10.Cu" signal "GND4")
		(24 "In11.Cu" signal "IN4")
		(26 "In12.Cu" signal "GND5")
		(28 "In13.Cu" signal "IN5")
		(30 "In14.Cu" signal "GND6")
		(32 "In15.Cu" signal "IN6")
		(34 "In16.Cu" signal "GND7")
		(2 "B.Cu" signal "BOTTOM")
		(9 "F.Adhes" user "F.Adhesive")
		(11 "B.Adhes" user "B.Adhesive")
		(13 "F.Paste" user "Package Geometry/Pastemask Top")
		(15 "B.Paste" user "Package Geometry/Pastemask Bottom")
		(5 "F.SilkS" user "Ref Des/Silkscreen Top")
		(7 "B.SilkS" user "Ref Des/Silkscreen Bottom")
		(1 "F.Mask" user "Board Geometry/Soldermask Top")
		(3 "B.Mask" user "Board Geometry/Soldermask Bottom")
		(17 "Dwgs.User" user "User.Drawings")
		(19 "Cmts.User" user "User.Comments")
		(21 "Eco1.User" user "User.Eco1")
		(23 "Eco2.User" user "User.Eco2")
		(25 "Edge.Cuts" user "Board Geometry/Outline")
		(27 "Margin" user)
		(31 "F.CrtYd" user "Package Geometry/Place Bound Top")
		(29 "B.CrtYd" user "Package Geometry/Place Bound Bottom")
		(35 "F.Fab" user "Ref Des/Assembly Top")
		(33 "B.Fab" user "Ref Des/Assembly Bottom")
	)
	(footprint ""
		(layer "F.Cu")
		(at 250.868688 -149.313392 -90)
		(property "Reference" "U83"
			(at 0.012192 -2.472182 90)
			(unlocked yes)
			(layer "F.SilkS")
			(effects
				(font
					(size 0.7874 0.5842)
					(thickness 0.1524)
				)
			)
		)
		(property "Value" ""
			(at 0 0 270)
			(layer "F.Fab")
			(effects
				(font
					(size 1.27 1.27)
				)
			)
		)
		(duplicate_pad_numbers_are_jumpers no)
		(fp_line
			(start -1.500124 1.500124)
			(end -1.500124 1.004062)
			(stroke
				(width 0.1524)
				(type default)
			)
			(layer "F.SilkS")
		)
		(fp_line
			(start -1.004062 1.500124)
			(end -1.500124 1.500124)
			(stroke
				(width 0.1524)
				(type default)
			)
			(layer "F.SilkS")
		)
		(fp_line
			(start 1.500124 1.500124)
			(end 1.004062 1.500124)
			(stroke
				(width 0.1524)
				(type default)
			)
			(layer "F.SilkS")
		)
		(fp_line
			(start 1.500124 1.004062)
			(end 1.500124 1.500124)
			(stroke
				(width 0.1524)
				(type default)
			)
			(layer "F.SilkS")
		)
		(fp_line
			(start -1.500124 -1.004062)
			(end -1.500124 -1.500124)
			(stroke
				(width 0.1524)
				(type default)
			)
			(layer "F.SilkS")
		)
		(fp_line
			(start -1.500124 -1.500124)
			(end -1.004062 -1.500124)
			(stroke
				(width 0.1524)
				(type default)
			)
			(layer "F.SilkS")
		)
		(fp_line
			(start 1.004062 -1.500124)
			(end 1.500124 -1.500124)
			(stroke
				(width 0.1524)
				(type default)
			)
			(layer "F.SilkS")
		)
		(fp_line
			(start 1.500124 -1.500124)
			(end 1.500124 -1.004062)
			(stroke
				(width 0.1524)
				(type default)
			)
			(layer "F.SilkS")
		)
		(fp_poly
			(pts
				(xy -1.975104 -2.088388) (xy -2.693416 -1.369822) (xy -1.615948 -1.010666)
			)
			(stroke
				(width 0)
				(type default)
			)
			(fill yes)
			(layer "F.SilkS")
		)
		(fp_line
			(start -1.500124 1.500124)
			(end -1.500124 -1.500124)
			(stroke
				(width 0.1)
				(type default)
			)
			(layer "F.Fab")
		)
		(fp_line
			(start 1.500124 1.500124)
			(end -1.500124 1.500124)
			(stroke
				(width 0.1)
				(type default)
			)
			(layer "F.Fab")
		)
		(fp_line
			(start -1.500124 -1.500124)
			(end 1.500124 -1.500124)
			(stroke
				(width 0.1)
				(type default)
			)
			(layer "F.Fab")
		)
		(fp_line
			(start 1.500124 -1.500124)
			(end 1.500124 1.500124)
			(stroke
				(width 0.1)
				(type default)
			)
			(layer "F.Fab")
		)
		(fp_poly
			(pts
				(xy -2.847848 -1.258062) (xy -2.847848 -0.242062) (xy -1.831848 -0.750062)
			)
			(stroke
				(width 0)
				(type default)
			)
			(fill yes)
			(layer "F.Fab")
		)
		(pad "1" smd rect
			(at -1.400048 -0.750062 180)
			(size 0.2286 0.6096)
			(layers "F.Cu" "F.Mask" "F.Paste")
			(net "NIC4_ADC_A1")
		)
		(pad "2" smd rect
			(at -1.400048 -0.249936 180)
			(size 0.2286 0.6096)
			(layers "F.Cu" "F.Mask" "F.Paste")
			(net "NIC4_ADC_A0")
		)
		(pad "3" smd rect
			(at -1.400048 0.249936 180)
			(size 0.2286 0.6096)
			(layers "F.Cu" "F.Mask" "F.Paste")
			(net "NIC4_ADC_ALERT_N")
		)
		(pad "4" smd rect
			(at -1.400048 0.750062 180)
			(size 0.2286 0.6096)
			(layers "F.Cu" "F.Mask" "F.Paste")
			(net "SMB_NIC4_ADC_SDA")
		)
		(pad "5" smd rect
			(at -0.750062 1.400048 270)
			(size 0.2286 0.6096)
			(layers "F.Cu" "F.Mask" "F.Paste")
			(net "SMB_NIC4_ADC_SCL")
		)
		(pad "6" smd rect
			(at -0.249936 1.400048 270)
			(size 0.2286 0.6096)
			(layers "F.Cu" "F.Mask" "F.Paste")
			(net "Net_8642")
		)
		(pad "7" smd rect
			(at 0.249936 1.400048 270)
			(size 0.2286 0.6096)
			(layers "F.Cu" "F.Mask" "F.Paste")
			(net "Net_8641")
		)
		(pad "8" smd rect
			(at 0.750062 1.400048 270)
			(size 0.2286 0.6096)
			(layers "F.Cu" "F.Mask" "F.Paste")
			(net "Net_8640")
		)
		(pad "9" smd rect
			(at 1.400048 0.750062 180)
			(size 0.2286 0.6096)
			(layers "F.Cu" "F.Mask" "F.Paste")
			(net "P3V3_AUX")
		)
		(pad "10" smd rect
			(at 1.400048 0.249936 180)
			(size 0.2286 0.6096)
			(layers "F.Cu" "F.Mask" "F.Paste")
			(net "GND")
		)
		(pad "11" smd rect
			(at 1.400048 -0.249936 180)
			(size 0.2286 0.6096)
			(layers "F.Cu" "F.Mask" "F.Paste")
			(net "P12V_NIC4_R")
		)
		(pad "12" smd rect
			(at 1.400048 -0.750062 180)
			(size 0.2286 0.6096)
			(layers "F.Cu" "F.Mask" "F.Paste")
			(net "P12V_NIC4_VIN_N")
		)
		(pad "13" smd rect
			(at 0.750062 -1.400048 270)
			(size 0.2286 0.6096)
			(layers "F.Cu" "F.Mask" "F.Paste")
			(net "P12V_NIC4_VIN_P")
		)
		(pad "14" smd rect
			(at 0.249936 -1.400048 270)
			(size 0.2286 0.6096)
			(layers "F.Cu" "F.Mask" "F.Paste")
			(net "Net_8639")
		)
		(pad "15" smd rect
			(at -0.249936 -1.400048 270)
			(size 0.2286 0.6096)
			(layers "F.Cu" "F.Mask" "F.Paste")
			(net "Net_8638")
		)
		(pad "16" smd rect
			(at -0.750062 -1.400048 270)
			(size 0.2286 0.6096)
			(layers "F.Cu" "F.Mask" "F.Paste")
			(net "Net_8637")
		)
		(pad "TH" smd rect
			(at 0 0 270)
			(size 1.7018 1.7018)
			(layers "F.Cu" "F.Mask" "F.Paste")
			(net "GND")
		)
		(zone
			(layer "F.Cu")
			(hatch none 0.5)
			(connect_pads
				(clearance 0)
			)
			(min_thickness 0.25)
			(keepout
				(tracks not_allowed)
				(vias allowed)
				(pads allowed)
				(copperpour not_allowed)
				(footprints allowed)
			)
			(placement
				(enabled no)
				(sheetname "")
			)
			(fill
				(thermal_gap 0.5)
				(thermal_bridge_width 0.5)
				(island_removal_mode 0)
			)
			(polygon
				(pts
					(xy 250.894088 -150.35784) (xy 251.913136 -150.35784) (xy 251.913136 -148.268944) (xy 249.82424 -148.268944)
					(xy 249.82424 -150.35784) (xy 250.868688 -150.35784) (xy 250.868688 -150.215092) (xy 249.966988 -150.215092)
					(xy 249.966988 -148.411692) (xy 251.770388 -148.411692) (xy 251.770388 -150.215092) (xy 250.894088 -150.215092)
				)
			)
		)
	)
	(footprint ""
		(layer "F.Cu")
		(at 187.626752 -55.418228 90)
		(property "Reference" "PC382"
			(at 0 0 90)
			(layer "F.SilkS")
			(hide yes)
			(effects
				(font
					(size 1.27 1.27)
				)
			)
		)
		(property "Value" ""
			(at 0 0 90)
			(layer "F.Fab")
			(effects
				(font
					(size 1.27 1.27)
				)
			)
		)
		(duplicate_pad_numbers_are_jumpers no)
		(fp_line
			(start 0.7874 -0.4064)
			(end 0.7874 0.4064)
			(stroke
				(width 0.1524)
				(type default)
			)
			(layer "F.SilkS")
		)
		(fp_line
			(start -0.7874 -0.4064)
			(end 0.7874 -0.4064)
			(stroke
				(width 0.1524)
				(type default)
			)
			(layer "F.SilkS")
		)
		(fp_line
			(start 0.7874 0.4064)
			(end -0.7874 0.4064)
			(stroke
				(width 0.1524)
				(type default)
			)
			(layer "F.SilkS")
		)
		(fp_line
			(start -0.7874 0.4064)
			(end -0.7874 -0.4064)
			(stroke
				(width 0.1524)
				(type default)
			)
			(layer "F.SilkS")
		)
		(fp_line
			(start -0.12065 -0.305054)
			(end -0.12065 -0.2794)
			(stroke
				(width 0.1)
				(type default)
			)
			(layer "F.Fab")
		)
		(fp_line
			(start -0.67945 -0.305054)
			(end -0.12065 -0.305054)
			(stroke
				(width 0.1)
				(type default)
			)
			(layer "F.Fab")
		)
		(fp_line
			(start 0.67945 -0.3048)
			(end 0.67945 0.3048)
			(stroke
				(width 0.1)
				(type default)
			)
			(layer "F.Fab")
		)
		(fp_line
			(start 0.12065 -0.3048)
			(end 0.67945 -0.3048)
			(stroke
				(width 0.1)
				(type default)
			)
			(layer "F.Fab")
		)
		(fp_line
			(start 0.12065 -0.2794)
			(end 0.12065 -0.3048)
			(stroke
				(width 0.1)
				(type default)
			)
			(layer "F.Fab")
		)
		(fp_line
			(start -0.12065 -0.2794)
			(end 0.12065 -0.2794)
			(stroke
				(width 0.1)
				(type default)
			)
			(layer "F.Fab")
		)
		(fp_line
			(start 0.120396 0.2794)
			(end -0.12065 0.2794)
			(stroke
				(width 0.1)
				(type default)
			)
			(layer "F.Fab")
		)
		(fp_line
			(start -0.12065 0.2794)
			(end -0.12065 0.3048)
			(stroke
				(width 0.1)
				(type default)
			)
			(layer "F.Fab")
		)
		(fp_line
			(start 0.67945 0.3048)
			(end 0.120396 0.3048)
			(stroke
				(width 0.1)
				(type default)
			)
			(layer "F.Fab")
		)
		(fp_line
			(start 0.120396 0.3048)
			(end 0.120396 0.2794)
			(stroke
				(width 0.1)
				(type default)
			)
			(layer "F.Fab")
		)
		(fp_line
			(start -0.12065 0.3048)
			(end -0.67945 0.3048)
			(stroke
				(width 0.1)
				(type default)
			)
			(layer "F.Fab")
		)
		(fp_line
			(start -0.67945 0.3048)
			(end -0.67945 -0.305054)
			(stroke
				(width 0.1)
				(type default)
			)
			(layer "F.Fab")
		)
		(pad "1" smd circle
			(at -0.40005 0 90)
			(size 0 0)
			(layers "F.Cu" "F.Mask" "F.Paste")
			(net "P12V_SSD6_R")
		)
		(pad "2" smd circle
			(at 0.40005 0 90)
			(size 0 0)
			(layers "F.Cu" "F.Mask" "F.Paste")
			(net "GND")
		)
	)
	(footprint ""
		(layer "F.Cu")
		(at 270.807942 -153.3144 180)
		(property "Reference" "R229"
			(at 0 0 180)
			(layer "F.SilkS")
			(hide yes)
			(effects
				(font
					(size 1.27 1.27)
				)
			)
		)
		(property "Value" ""
			(at 0 0 180)
			(layer "F.Fab")
			(effects
				(font
					(size 1.27 1.27)
				)
			)
		)
		(duplicate_pad_numbers_are_jumpers no)
		(fp_line
			(start 0.7874 0.4064)
			(end -0.7874 0.4064)
			(stroke
				(width 0.1524)
				(type default)
			)
			(layer "F.SilkS")
		)
		(fp_line
			(start 0.7874 -0.4064)
			(end 0.7874 0.4064)
			(stroke
				(width 0.1524)
				(type default)
			)
			(layer "F.SilkS")
		)
		(fp_line
			(start -0.7874 0.4064)
			(end -0.7874 -0.4064)
			(stroke
				(width 0.1524)
				(type default)
			)
			(layer "F.SilkS")
		)
		(fp_line
			(start -0.7874 -0.4064)
			(end 0.7874 -0.4064)
			(stroke
				(width 0.1524)
				(type default)
			)
			(layer "F.SilkS")
		)
		(fp_line
			(start 0.67945 0.3048)
			(end 0.120396 0.3048)
			(stroke
				(width 0.1)
				(type default)
			)
			(layer "F.Fab")
		)
		(fp_line
			(start 0.67945 -0.3048)
			(end 0.67945 0.3048)
			(stroke
				(width 0.1)
				(type default)
			)
			(layer "F.Fab")
		)
		(fp_line
			(start 0.12065 -0.2794)
			(end 0.12065 -0.3048)
			(stroke
				(width 0.1)
				(type default)
			)
			(layer "F.Fab")
		)
		(fp_line
			(start 0.12065 -0.3048)
			(end 0.67945 -0.3048)
			(stroke
				(width 0.1)
				(type default)
			)
			(layer "F.Fab")
		)
		(fp_line
			(start 0.120396 0.3048)
			(end 0.120396 0.2794)
			(stroke
				(width 0.1)
				(type default)
			)
			(layer "F.Fab")
		)
		(fp_line
			(start 0.120396 0.2794)
			(end -0.12065 0.2794)
			(stroke
				(width 0.1)
				(type default)
			)
			(layer "F.Fab")
		)
		(fp_line
			(start -0.12065 0.3048)
			(end -0.67945 0.3048)
			(stroke
				(width 0.1)
				(type default)
			)
			(layer "F.Fab")
		)
		(fp_line
			(start -0.12065 0.2794)
			(end -0.12065 0.3048)
			(stroke
				(width 0.1)
				(type default)
			)
			(layer "F.Fab")
		)
		(fp_line
			(start -0.12065 -0.2794)
			(end 0.12065 -0.2794)
			(stroke
				(width 0.1)
				(type default)
			)
			(layer "F.Fab")
		)
		(fp_line
			(start -0.12065 -0.305054)
			(end -0.12065 -0.2794)
			(stroke
				(width 0.1)
				(type default)
			)
			(layer "F.Fab")
		)
		(fp_line
			(start -0.67945 0.3048)
			(end -0.67945 -0.305054)
			(stroke
				(width 0.1)
				(type default)
			)
			(layer "F.Fab")
		)
		(fp_line
			(start -0.67945 -0.305054)
			(end -0.12065 -0.305054)
			(stroke
				(width 0.1)
				(type default)
			)
			(layer "F.Fab")
		)
		(pad "1" smd circle
			(at -0.40005 0 180)
			(size 0 0)
			(layers "F.Cu" "F.Mask" "F.Paste")
			(net "NIC4_SLOT_ID0")
		)
		(pad "2" smd circle
			(at 0.40005 0 180)
			(size 0 0)
			(layers "F.Cu" "F.Mask" "F.Paste")
			(net "P3V3_NIC4")
		)
	)
	(footprint ""
		(layer "F.Cu")
		(at 292.743382 -343.952322 90)
		(property "Reference" "C2363"
			(at 0 0 90)
			(layer "F.SilkS")
			(hide yes)
			(effects
				(font
					(size 1.27 1.27)
				)
			)
		)
		(property "Value" ""
			(at 0 0 90)
			(layer "F.Fab")
			(effects
				(font
					(size 1.27 1.27)
				)
			)
		)
		(duplicate_pad_numbers_are_jumpers no)
		(fp_line
			(start 0.299974 -0.150114)
			(end 0.299974 0.150114)
			(stroke
				(width 0.1)
				(type default)
			)
			(layer "F.Fab")
		)
		(fp_line
			(start -0.299974 -0.150114)
			(end 0.299974 -0.150114)
			(stroke
				(width 0.1)
				(type default)
			)
			(layer "F.Fab")
		)
		(fp_line
			(start 0.299974 0.150114)
			(end -0.299974 0.150114)
			(stroke
				(width 0.1)
				(type default)
			)
			(layer "F.Fab")
		)
		(fp_line
			(start -0.299974 0.150114)
			(end -0.299974 -0.150114)
			(stroke
				(width 0.1)
				(type default)
			)
			(layer "F.Fab")
		)
		(pad "1" smd rect
			(at -0.2667 0 90)
			(size 0.3048 0.381)
			(layers "F.Cu" "F.Mask" "F.Paste")
			(net "P5E_PEX2_STN4_TX_DP<68>")
		)
		(pad "2" smd rect
			(at 0.2667 0 90)
			(size 0.3048 0.381)
			(layers "F.Cu" "F.Mask" "F.Paste")
			(net "P5E_PEX2_STN4_TX_C_DP<68>")
		)
	)
	(footprint ""
		(layer "F.Cu")
		(at 336.042 -173.101 180)
		(property "Reference" "R4765"
			(at 0 0 180)
			(layer "F.SilkS")
			(hide yes)
			(effects
				(font
					(size 1.27 1.27)
				)
			)
		)
		(property "Value" ""
			(at 0 0 180)
			(layer "F.Fab")
			(effects
				(font
					(size 1.27 1.27)
				)
			)
		)
		(duplicate_pad_numbers_are_jumpers no)
		(fp_line
			(start 0.7874 0.4064)
			(end -0.7874 0.4064)
			(stroke
				(width 0.1524)
				(type default)
			)
			(layer "F.SilkS")
		)
		(fp_line
			(start 0.7874 -0.4064)
			(end 0.7874 0.4064)
			(stroke
				(width 0.1524)
				(type default)
			)
			(layer "F.SilkS")
		)
		(fp_line
			(start -0.7874 0.4064)
			(end -0.7874 -0.4064)
			(stroke
				(width 0.1524)
				(type default)
			)
			(layer "F.SilkS")
		)
		(fp_line
			(start -0.7874 -0.4064)
			(end 0.7874 -0.4064)
			(stroke
				(width 0.1524)
				(type default)
			)
			(layer "F.SilkS")
		)
		(fp_line
			(start 0.67945 0.3048)
			(end 0.120396 0.3048)
			(stroke
				(width 0.1)
				(type default)
			)
			(layer "F.Fab")
		)
		(fp_line
			(start 0.67945 -0.3048)
			(end 0.67945 0.3048)
			(stroke
				(width 0.1)
				(type default)
			)
			(layer "F.Fab")
		)
		(fp_line
			(start 0.12065 -0.2794)
			(end 0.12065 -0.3048)
			(stroke
				(width 0.1)
				(type default)
			)
			(layer "F.Fab")
		)
		(fp_line
			(start 0.12065 -0.3048)
			(end 0.67945 -0.3048)
			(stroke
				(width 0.1)
				(type default)
			)
			(layer "F.Fab")
		)
		(fp_line
			(start 0.120396 0.3048)
			(end 0.120396 0.2794)
			(stroke
				(width 0.1)
				(type default)
			)
			(layer "F.Fab")
		)
		(fp_line
			(start 0.120396 0.2794)
			(end -0.12065 0.2794)
			(stroke
				(width 0.1)
				(type default)
			)
			(layer "F.Fab")
		)
		(fp_line
			(start -0.12065 0.3048)
			(end -0.67945 0.3048)
			(stroke
				(width 0.1)
				(type default)
			)
			(layer "F.Fab")
		)
		(fp_line
			(start -0.12065 0.2794)
			(end -0.12065 0.3048)
			(stroke
				(width 0.1)
				(type default)
			)
			(layer "F.Fab")
		)
		(fp_line
			(start -0.12065 -0.2794)
			(end 0.12065 -0.2794)
			(stroke
				(width 0.1)
				(type default)
			)
			(layer "F.Fab")
		)
		(fp_line
			(start -0.12065 -0.305054)
			(end -0.12065 -0.2794)
			(stroke
				(width 0.1)
				(type default)
			)
			(layer "F.Fab")
		)
		(fp_line
			(start -0.67945 0.3048)
			(end -0.67945 -0.305054)
			(stroke
				(width 0.1)
				(type default)
			)
			(layer "F.Fab")
		)
		(fp_line
			(start -0.67945 -0.305054)
			(end -0.12065 -0.305054)
			(stroke
				(width 0.1)
				(type default)
			)
			(layer "F.Fab")
		)
		(pad "1" smd circle
			(at -0.40005 0 180)
			(size 0 0)
			(layers "F.Cu" "F.Mask" "F.Paste")
			(net "PCA9555_1_PEX2_A1")
		)
		(pad "2" smd circle
			(at 0.40005 0 180)
			(size 0 0)
			(layers "F.Cu" "F.Mask" "F.Paste")
			(net "P3V3_AUX")
		)
	)
	(footprint ""
		(layer "F.Cu")
		(at 349.426276 -39.73576 -90)
		(property "Reference" "R5566"
			(at 0 0 270)
			(layer "F.SilkS")
			(hide yes)
			(effects
				(font
					(size 1.27 1.27)
				)
			)
		)
		(property "Value" ""
			(at 0 0 270)
			(layer "F.Fab")
			(effects
				(font
					(size 1.27 1.27)
				)
			)
		)
		(duplicate_pad_numbers_are_jumpers no)
		(fp_line
			(start -0.7874 0.4064)
			(end -0.7874 -0.4064)
			(stroke
				(width 0.1524)
				(type default)
			)
			(layer "F.SilkS")
		)
		(fp_line
			(start 0.7874 0.4064)
			(end -0.7874 0.4064)
			(stroke
				(width 0.1524)
				(type default)
			)
			(layer "F.SilkS")
		)
		(fp_line
			(start -0.7874 -0.4064)
			(end 0.7874 -0.4064)
			(stroke
				(width 0.1524)
				(type default)
			)
			(layer "F.SilkS")
		)
		(fp_line
			(start 0.7874 -0.4064)
			(end 0.7874 0.4064)
			(stroke
				(width 0.1524)
				(type default)
			)
			(layer "F.SilkS")
		)
		(fp_line
			(start -0.67945 0.3048)
			(end -0.67945 -0.305054)
			(stroke
				(width 0.1)
				(type default)
			)
			(layer "F.Fab")
		)
		(fp_line
			(start -0.12065 0.3048)
			(end -0.67945 0.3048)
			(stroke
				(width 0.1)
				(type default)
			)
			(layer "F.Fab")
		)
		(fp_line
			(start 0.120396 0.3048)
			(end 0.120396 0.2794)
			(stroke
				(width 0.1)
				(type default)
			)
			(layer "F.Fab")
		)
		(fp_line
			(start 0.67945 0.3048)
			(end 0.120396 0.3048)
			(stroke
				(width 0.1)
				(type default)
			)
			(layer "F.Fab")
		)
		(fp_line
			(start -0.12065 0.2794)
			(end -0.12065 0.3048)
			(stroke
				(width 0.1)
				(type default)
			)
			(layer "F.Fab")
		)
		(fp_line
			(start 0.120396 0.2794)
			(end -0.12065 0.2794)
			(stroke
				(width 0.1)
				(type default)
			)
			(layer "F.Fab")
		)
		(fp_line
			(start -0.12065 -0.2794)
			(end 0.12065 -0.2794)
			(stroke
				(width 0.1)
				(type default)
			)
			(layer "F.Fab")
		)
		(fp_line
			(start 0.12065 -0.2794)
			(end 0.12065 -0.3048)
			(stroke
				(width 0.1)
				(type default)
			)
			(layer "F.Fab")
		)
		(fp_line
			(start 0.12065 -0.3048)
			(end 0.67945 -0.3048)
			(stroke
				(width 0.1)
				(type default)
			)
			(layer "F.Fab")
		)
		(fp_line
			(start 0.67945 -0.3048)
			(end 0.67945 0.3048)
			(stroke
				(width 0.1)
				(type default)
			)
			(layer "F.Fab")
		)
		(fp_line
			(start -0.67945 -0.305054)
			(end -0.12065 -0.305054)
			(stroke
				(width 0.1)
				(type default)
			)
			(layer "F.Fab")
		)
		(fp_line
			(start -0.12065 -0.305054)
			(end -0.12065 -0.2794)
			(stroke
				(width 0.1)
				(type default)
			)
			(layer "F.Fab")
		)
		(pad "1" smd circle
			(at -0.40005 0 270)
			(size 0 0)
			(layers "F.Cu" "F.Mask" "F.Paste")
			(net "P3V3_AUX")
		)
		(pad "2" smd circle
			(at 0.40005 0 270)
			(size 0 0)
			(layers "F.Cu" "F.Mask" "F.Paste")
			(net "SSD12_AUX_P3V3_EN")
		)
	)
)
